#ISCELL
  mstr_misc dns *
  *
#ISCELL
  pure_quanta quanta_title_block_c *
  *
#ISCELL
  standard offpage *
  page214_i100
#CELL
  pure_quanta q_res *
  page214_i101
#ISCELL
  standard offpage *
  page214_i113
#ISCELL
  standard offpage *
  page214_i114
#ISCELL
  standard offpage *
  page214_i115
#ISCELL
  standard offpage *
  page214_i116
#ISCELL
  standard offpage *
  page214_i117
#CELL
  pure_quanta q_res *
  page214_i118
#ISCELL
  standard offpage *
  page214_i122
#ISCELL
  standard offpage *
  page214_i123
#ISCELL
  standard offpage *
  page214_i124
#CELL
  pure_quanta q_res *
  page214_i127
#CELL
  pure_quanta q_res *
  page214_i128
#CELL
  pure_quanta q_res *
  page214_i129
#ISCELL
  standard offpage *
  page214_i130
#ISCELL
  standard offpage *
  page214_i131
#ISCELL
  standard offpage *
  page214_i132
#ISCELL
  standard offpage *
  page214_i133
#ISCELL
  standard offpage *
  page214_i134
#ISCELL
  standard offpage *
  page214_i135
#ISCELL
  standard offpage *
  page214_i136
#CELL
  pure_quanta q_res *
  page214_i137
#ISCELL
  standard offpage *
  page214_i138
#ISCELL
  standard offpage *
  page214_i139
#CELL
  pure_quanta q_res *
  page214_i140
#ISCELL
  standard offpage *
  page214_i141
#ISCELL
  standard offpage *
  page214_i142
#ISCELL
  standard offpage *
  page214_i143
#CELL
  pure_quanta q_res *
  page214_i144
#ISCELL
  standard offpage *
  page214_i145
#ISCELL
  standard offpage *
  page214_i146
#ISCELL
  standard offpage *
  page214_i147
#CELL
  pure_quanta q_res *
  page214_i148
#ISCELL
  standard offpage *
  page214_i149
#ISCELL
  standard offpage *
  page214_i150
#ISCELL
  standard offpage *
  page214_i151
#ISCELL
  standard offpage *
  page214_i152
#CELL
  pure_quanta q_res *
  page214_i153
#ISCELL
  standard offpage *
  page214_i154
#ISCELL
  standard offpage *
  page214_i155
#CELL
  pure_quanta q_res *
  page214_i156
#ISCELL
  standard offpage *
  page214_i157
#ISCELL
  standard offpage *
  page214_i158
#ISCELL
  standard offpage *
  page214_i159
#ISCELL
  standard offpage *
  page214_i160
#CELL
  pure_quanta q_res *
  page214_i161
#ISCELL
  standard offpage *
  page214_i162
#ISCELL
  standard offpage *
  page214_i163
#CELL
  pure_quanta q_res *
  page214_i164
#ISCELL
  standard offpage *
  page214_i165
#ISCELL
  standard offpage *
  page214_i166
#ISCELL
  standard offpage *
  page214_i167
#ISCELL
  standard offpage *
  page214_i33
#CELL
  pure_quanta q_res *
  page214_i34
#ISCELL
  standard offpage *
  page214_i35
#CELL
  pure_quanta pca9539rpw *
  page214_i66
#ISCELL
  logical_power universal_power *
  page214_i73
#CELL
  pure_quanta q_res *
  page214_i74
#CELL
  pure_quanta q_res *
  page214_i75
#CELL
  pure_quanta q_res *
  page214_i76
#CELL
  pure_quanta q_res *
  page214_i77
#ISCELL
  logical_power universal_gnd *
  page214_i78
#ISCELL
  logical_power universal_gnd *
  page214_i79
#ISCELL
  standard offpage *
  page214_i80
#ISCELL
  standard offpage *
  page214_i81
#ISCELL
  standard offpage *
  page214_i82
#ISCELL
  standard offpage *
  page214_i83
#ISCELL
  standard offpage *
  page214_i84
#ISCELL
  standard offpage *
  page214_i85
#ISCELL
  logical_power universal_gnd *
  page214_i86
#CELL
  pure_quanta q_cap *
  page214_i87
#ISCELL
  logical_power universal_power *
  page214_i88
#ISCELL
  logical_power universal_gnd *
  page214_i89
#CELL
  pure_quanta q_res *
  page214_i90
#ISCELL
  logical_power universal_power *
  page214_i91
#ISCELL
  standard offpage *
  page214_i92
#CELL
  pure_quanta q_res *
  page214_i93
#ISCELL
  logical_power universal_power *
  page214_i94
#CELL
  pure_quanta q_res *
  page214_i95
#CELL
  pure_quanta q_res *
  page214_i96
#ISCELL
  standard offpage *
  page214_i97
#ISCELL
  standard offpage *
  page214_i98
#ISCELL
  standard offpage *
  page214_i99
